#ISCELL
  mstr_symbols intel_corp_bpage *
  *
#ISCELL
  mstr_symbols gnd *
  page271_i10
#CELL
  w_hdl tpad-diff-4p-gp *
  page271_i11
#ISCELL
  mstr_symbols gnd *
  page271_i12
#CELL
  w_hdl tpad-diff-4p-gp *
  page271_i13
#ISCELL
  mstr_symbols gnd *
  page271_i14
#CELL
  w_hdl tpad-diff-4p-gp *
  page271_i15
#CELL
  w_hdl tpad-diff-4p-gp *
  page271_i16
#CELL
  w_hdl tpad-diff-4p-gp *
  page271_i17
#ISCELL
  mstr_symbols gnd *
  page271_i18
#CELL
  w_hdl tpad-diff-4p-gp *
  page271_i19
#ISCELL
  mstr_symbols gnd *
  page271_i20
#ISCELL
  mstr_symbols gnd *
  page271_i21
#ISCELL
  mstr_symbols gnd *
  page271_i22
#CELL
  w_hdl tpad-diff-4p-gp *
  page271_i23
#CELL
  w_hdl tpad-diff-4p-gp *
  page271_i24
#ISCELL
  mstr_symbols gnd *
  page271_i25
#ISCELL
  mstr_symbols gnd *
  page271_i26
#CELL
  w_hdl tpad-diff-4p-gp *
  page271_i3
#CELL
  w_hdl tpad-diff-4p-gp *
  page271_i30
#ISCELL
  mstr_symbols gnd *
  page271_i32
#CELL
  w_hdl tpad-diff-4p-gp *
  page271_i36
#ISCELL
  mstr_symbols gnd *
  page271_i37
#CELL
  w_hdl tpad-diff-4p-gp *
  page271_i38
#CELL
  w_hdl tpad-diff-4p-gp *
  page271_i39
#ISCELL
  mstr_symbols gnd *
  page271_i4
#ISCELL
  mstr_symbols gnd *
  page271_i40
#CELL
  w_hdl tpad-diff-4p-gp *
  page271_i45
#ISCELL
  mstr_symbols gnd *
  page271_i46
#CELL
  w_hdl tpad-diff-4p-gp *
  page271_i47
#ISCELL
  mstr_symbols gnd *
  page271_i48
#ISCELL
  mstr_symbols gnd *
  page271_i49
#CELL
  w_hdl tpad-diff-4p-gp *
  page271_i5
#CELL
  w_hdl tpad-se-2p-gp *
  page271_i50
#ISCELL
  mstr_symbols gnd *
  page271_i51
#CELL
  w_hdl tpad-se-2p-gp *
  page271_i52
#ISCELL
  mstr_symbols gnd *
  page271_i53
#CELL
  w_hdl tpad-se-2p-gp *
  page271_i54
#ISCELL
  mstr_symbols gnd *
  page271_i55
#CELL
  w_hdl tpad-se-2p-gp *
  page271_i56
#ISCELL
  mstr_symbols gnd *
  page271_i57
#ISCELL
  mstr_symbols gnd *
  page271_i58
#ISCELL
  mstr_symbols gnd *
  page271_i59
#ISCELL
  mstr_symbols gnd *
  page271_i6
#CELL
  w_hdl tpad-se-2p-gp *
  page271_i60
#CELL
  w_hdl tpad-se-2p-gp *
  page271_i61
#CELL
  w_hdl tpad-se-2p-gp *
  page271_i62
#CELL
  w_hdl tpad-se-2p-gp *
  page271_i63
#ISCELL
  mstr_symbols gnd *
  page271_i64
#ISCELL
  mstr_symbols gnd *
  page271_i65
#ISCELL
  mstr_symbols gnd *
  page271_i66
#CELL
  w_hdl tpad-se-2p-gp *
  page271_i67
#ISCELL
  mstr_symbols gnd *
  page271_i68
#ISCELL
  mstr_symbols gnd *
  page271_i69
#CELL
  w_hdl tpad-diff-4p-gp *
  page271_i7
#ISCELL
  mstr_symbols gnd *
  page271_i70
#CELL
  w_hdl tpad-se-2p-gp *
  page271_i71
#CELL
  w_hdl tpad-se-2p-gp *
  page271_i72
#CELL
  w_hdl tpad-se-2p-gp *
  page271_i73
#CELL
  w_hdl tpad-diff-4p-gp *
  page271_i8
#ISCELL
  mstr_symbols gnd *
  page271_i9
